FILE_TYPE = CONNECTIVITY;
{Allegro Design Entry HDL 16.6-p007 (v16-6-112F) 10/10/2012}
"PAGE_NUMBER" = 157;
0"NC";
1"P3V3_STBY\g";
2"P3V3\g";
3"GND\g";
4"P3V3_STBY\g";
5"P3V3_STBY\g";
6"GND\g";
7"P3V3_STBY\g";
8"GND\g";
9"GND\g";
10"P3V3_STBY\g";
11"P3V3_STBY\g";
12"GND\g";
13"GND\g";
14"P3V3_STBY\g";
15"P3V3_STBY\g";
16"FM_TPM_PRES_RST_N";
17"FM_BMC_ENABLE_N";
18"H_CPU0_FAST_WAKE_LVT3_N";
19"RST_BMC_DDR3_BUF_IN_N";
20"FP_NMI_BTN_N";
21"FM_BMC_NMI_N";
22"FP_NMI_BTN_R_N";
23"RST_BMC_SRST_R2_N";
24"FM_NMI_EVENT_N";
25"FP_NMI_BTN";
26"FP_NMI_BTN_OUT_N";
27"FP_NMI_BTN_OUT_R_N";
28"PWRGD_DSW_PWROK";
29"FM_CPLD_BMC_PWRDN_N";
30"IRQ_MEZZ_LAN_ALERT_N";
31"FM_BMC_CPLD_MP_RST_N";
32"FM_BIOS_TOP_SWAP";
33"FM_BMC_CPLD_GPO";
34"FM_ADR_SMI_GPIO_N";
35"FM_MP_PS_REDUNDANT_LOST_N";
36"FM_MP_PS_FAIL_N";
37"FP_NMI_BTN_N";
38"IRQ_OOB_MGMT_RISER_ALERT_N";
39"H_CPU0_FAST_WAKE";
40"H_CPU0_FAST_WAKE_B_N";
41"H_CPU0_FAST_WAKE_N";
%"RES"
"1","(-7200,4225)","0","mstr_discrete","I296";
;
CDS_SEC"1"
CDS_LIB"mstr_discrete"
CDS_LOCATION"R8F23"
ROOM"BMC_MISC"
SEC"1"
SEC_TYPE"0402"
BOM_COST"SM_CONTROLLER"
VALUE"2.21K"
PART_NUMBER"G21796-112"
LOCATION"R8F23"
WATTAGE"1/16W"
MATERIAL"CHIP"
PACK_TYPE"0402"
TOLERANCE"1%";
"B"
$PN"2"30;
"A"
$PN"1"1;
%"P3V3_STBY"
"1","(-7525,4650)","0","mstr_symbols","I297";
;
HDL_POWER"P3V3_STBY"
BODY_TYPE"PLUMBING"
VOLTAGE"3.3V"
SIZE"1B"
CDS_LIB"mstr_symbols";
"G\NAC"1;
%"RES"
"1","(-7175,3975)","0","mstr_discrete","I298";
;
CDS_SEC"1"
CDS_LOCATION"R2T29"
CDS_LIB"mstr_discrete"
ROOM"BMC_MISC"
SEC"1"
SEC_TYPE"0402"
BOM_COST"SM_CONTROLLER"
VALUE"2.21K"
PART_NUMBER"G21796-112"
LOCATION"R2T29"
TOLERANCE"1%"
PACK_TYPE"0402"
MATERIAL"CHIP"
WATTAGE"1/16W";
"B"
$PN"2"38;
"A"
$PN"1"1;
%"RES"
"1","(-2050,3825)","0","mstr_discrete","I302";
;
CDS_SEC"1"
CDS_LIB"mstr_discrete"
SEC_TYPE"0402"
SEC"1"
CDS_LOCATION"R2N25"
ROOM"BMC_MISC"
BOM_COST"SM_CONTROLLER"
VALUE"51.1"
PART_NUMBER"G21796-208"
LOCATION"R2N25"
MATERIAL"CHIP"
TOLERANCE"1.0%"
WATTAGE"1/16W"
PACK_TYPE"0402";
"B"
$PN"2"21;
"A"
$PN"1"24;
%"P3V3"
"1","(-1850,4275)","0","mstr_symbols","I303";
;
HDL_POWER"P3V3"
VOLTAGE"3.3V"
SIZE"1B"
CDS_LIB"mstr_symbols"
BODY_TYPE"PLUMBING";
"G\NAC"2;
%"RES"
"1","(-7175,3725)","0","mstr_discrete","I316";
;
CDS_SEC"1"
CDS_LOCATION"R8F24"
CDS_LIB"mstr_discrete"
ROOM"BMC_MISC"
SEC_TYPE"0402"
SEC"1"
BOM_COST"SM_CONTROLLER"
VALUE"4.75K"
PART_NUMBER"G21796-072"
LOCATION"R8F24"
TOLERANCE"1%"
PACK_TYPE"0402"
MATERIAL"CHIP"
WATTAGE"1/16W";
"B"
$PN"2"37;
"A"
$PN"1"1;
%"GND"
"1","(-6225,525)","0","mstr_symbols","I322";
;
BODY_TYPE"PLUMBING"
SIZE"1B"
VOLTAGE"0.0V"
CDS_LIB"mstr_symbols"
HDL_POWER"GND";
"A\NAC"3;
%"RES"
"2","(-6225,1250)","0","mstr_discrete","I326";
;
CDS_SEC"1"
CDS_LIB"mstr_discrete"
CDS_LOCATION"R2T5"
ROOM"PROC_SIDEBAND"
SEC"1"
SEC_TYPE"0402"
BOM_COST"PROC_SIDEBAND"
WATTAGE"1/16W"
MATERIAL"CHIP"
PACK_TYPE"0402"
TOLERANCE"1%"
VALUE"1.00K"
PART_NUMBER"G21796-026"
LOCATION"R2T5";
"A"
$PN"1"4;
"B"
$PN"2"39;
%"RES"
"2","(-5575,1650)","0","mstr_discrete","I327";
;
CDS_SEC"1"
CDS_LIB"mstr_discrete"
CDS_LOCATION"R2T7"
ROOM"PROC_SIDEBAND"
SEC"1"
SEC_TYPE"0402"
BOM_COST"PROC_SIDEBAND"
PACK_TYPE"0402"
PART_NUMBER"G21796-026"
TOLERANCE"1%"
MATERIAL"CHIP"
WATTAGE"1/16W"
VALUE"1.00K"
LOCATION"R2T7";
"A"
$PN"1"5;
"B"
$PN"2"18;
%"P3V3_STBY"
"1","(-6225,1450)","0","mstr_symbols","I328";
;
HDL_POWER"P3V3_STBY"
BODY_TYPE"PLUMBING"
VOLTAGE"3.3V"
SIZE"1B"
CDS_LIB"mstr_symbols";
"G\NAC"4;
%"P3V3_STBY"
"1","(-5575,1875)","0","mstr_symbols","I329";
;
HDL_POWER"P3V3_STBY"
BODY_TYPE"PLUMBING"
SIZE"1B"
CDS_LIB"mstr_symbols"
VOLTAGE"3.3V";
"G\NAC"5;
%"NPN"
"1","(-6275,775)","0","mstr_discrete","I330";
;
CDS_SEC"1"
CDS_LIB"mstr_discrete"
ROOM"PROC_SIDEBAND"
CDS_LOCATION"Q2T1"
SEC"1"
SEC_TYPE"SM"
BOM_COST"PROC_SIDEBAND"
MATERIAL"IC"
PACK_TYPE"SM"
VALUE"MMBT3904"
PART_NUMBER"C52245-001"
LOCATION"Q2T1";
"C"
$PN"3"39;
"E"
$PN"2"3;
"B"
$PN"1"40;
%"GND"
"1","(-5575,775)","0","mstr_symbols","I333";
;
BODY_TYPE"PLUMBING"
SIZE"1B"
VOLTAGE"0.0V"
HDL_POWER"GND"
CDS_LIB"mstr_symbols";
"A\NAC"6;
%"RES"
"2","(-2275,1525)","0","mstr_discrete","I335";
;
CDS_SEC"1"
CDS_LIB"mstr_discrete"
CDS_LOCATION"R8D25"
SEC"1"
SEC_TYPE"0402"
ROOM"BMC_MISC"
BOM_COST"SM_CONTROLLER"
WATTAGE"1/16W"
MATERIAL"CHIP"
PACK_TYPE"0402"
VALUE"4.75K"
TOLERANCE"1%"
LOCATION"R8D25"
PART_NUMBER"G21796-072";
"A"
$PN"1"7;
"B"
$PN"2"23;
%"P3V3_STBY"
"1","(-2275,1725)","0","mstr_symbols","I339";
;
HDL_POWER"P3V3_STBY"
VOLTAGE"3.3V"
BODY_TYPE"PLUMBING"
CDS_LIB"mstr_symbols"
SIZE"1B";
"G\NAC"7;
%"FET_N"
"8","(-5575,1100)","0","mstr_discrete","I340";
;
CDS_SEC"1"
PACK_TYPE"SOT23LF"
CDS_LIB"mstr_discrete"
ROOM"PROC_SIDEBAND"
CDS_LOCATION"Q2T2"
SEC"1"
BOM_COST"PROC_SIDEBAND"
SEC_TYPE"SOT23LF"
MATERIAL"FET"
VALUE"2N7002"
LOCATION"Q2T2"
PART_NUMBER"C79254-001";
"GATE"
$PN"1"39;
"DRN"
$PN"3"18;
"SRC"
$PN"2"6;
%"RES"
"1","(-7175,3100)","0","mstr_discrete","I342";
;
CDS_SEC"1"
ROOM"BMC_MISC"
CDS_LOCATION"R3N12"
CDS_LIB"mstr_discrete"
BOM_COST"SM_CONTROLLER"
SEC"1"
SEC_TYPE"0402"
VALUE"4.75K"
PART_NUMBER"G21796-072"
LOCATION"R3N12"
MATERIAL"CHIP"
WATTAGE"1/16W"
PACK_TYPE"0402"
TOLERANCE"1%";
"B"
$PN"2"36;
"A"
$PN"1"1;
%"RES"
"1","(-7175,2875)","0","mstr_discrete","I344";
;
CDS_SEC"1"
ROOM"BMC_MISC"
CDS_LOCATION"R3N11"
BOM_COST"SM_CONTROLLER"
CDS_LIB"mstr_discrete"
SEC"1"
SEC_TYPE"0402"
VALUE"4.75K"
PART_NUMBER"G21796-072"
LOCATION"R3N11"
TOLERANCE"1%"
PACK_TYPE"0402"
MATERIAL"CHIP"
WATTAGE"1/16W";
"B"
$PN"2"35;
"A"
$PN"1"1;
%"RES"
"1","(-7175,2650)","0","mstr_discrete","I346";
;
CDS_SEC"1"
ROOM"BMC_MISC"
CDS_LOCATION"R2M2"
CDS_LIB"mstr_discrete"
BOM_COST"SM_CONTROLLER"
SEC"1"
SEC_TYPE"0402"
VALUE"4.75K"
PART_NUMBER"G21796-072"
LOCATION"R2M2"
MATERIAL"CHIP"
TOLERANCE"1%"
PACK_TYPE"0402"
WATTAGE"1/16W";
"B"
$PN"2"34;
"A"
$PN"1"1;
%"RES"
"1","(-7175,2425)","0","mstr_discrete","I348";
;
CDS_SEC"1"
CDS_LOCATION"R2M5"
CDS_LIB"mstr_discrete"
ROOM"BMC_MISC"
BOM_COST"SM_CONTROLLER"
SEC_TYPE"0402"
SEC"1"
VALUE"4.75K"
PART_NUMBER"G21796-072"
LOCATION"R2M5"
TOLERANCE"1%"
MATERIAL"CHIP"
PACK_TYPE"0402"
WATTAGE"1/16W";
"B"
$PN"2"33;
"A"
$PN"1"1;
%"SWITCH_D90553001"
"1","(-4375,2375)","0","mstr_misc","I351";
;
CDS_SEC"1"
CDS_LIB"mstr_misc"
ROOM"MIO_CHASSIS"
CDS_LOCATION"S8E1"
SEC"1"
SEC_TYPE"SMLF"
BOM_COST"MIO_CHASSIS"
PACK_TYPE"SMLF"
PART_NUMBER"D90553-001"
MATERIAL"IC"
LOCATION"S8E1"
PART_NAME"SWITCH_D90553001";
"B \B"
$PN"2"27;
"A \B"
$PN"1"9;
%"RES"
"1","(-3650,2375)","0","mstr_discrete","I352";
;
CDS_SEC"1"
CDS_LIB"mstr_discrete"
CDS_LOCATION"R2R9"
ROOM"MIO_CHASSIS"
SEC"1"
BOM_COST"MIO_CHASSIS"
SEC_TYPE"0402"
VALUE"200.0"
TOLERANCE"1%"
WATTAGE"1/16W"
MATERIAL"CHIP"
PART_NUMBER"G21796-004"
LOCATION"R2R9"
PACK_TYPE"0402";
"B"
$PN"2"26;
"A"
$PN"1"27;
%"CAP_A"
"1","(-3200,2150)","0","dev_discrete","I353";
;
CDS_LOCATION"C2R12"
CDS_LIB"dev_discrete"
CDS_SEC"1"
BOM_COST"MIO_CHASSIS"
SEC_TYPE"0402V"
SEC"1"
ROOM"MIO_CHASSIS"
PACK_TYPE"0402V"
PART_NUMBER"D97712-004"
MATERIAL"X6S"
VOLTAGE"6.3V"
TOLERANCE"10%"
VALUE"1.0UF"
LOCATION"C2R12";
"B"
$PN"2"8;
"A"
$PN"1"26;
%"GND"
"1","(-3200,1875)","0","mstr_symbols","I354";
;
BODY_TYPE"PLUMBING"
CDS_LIB"mstr_symbols"
SIZE"1B"
VOLTAGE"0.0V"
HDL_POWER"GND";
"A\NAC"8;
%"GND"
"1","(-4775,2200)","0","mstr_symbols","I355";
;
VOLTAGE"0.0V"
CDS_LIB"mstr_symbols"
SIZE"1B"
BODY_TYPE"PLUMBING"
HDL_POWER"GND";
"A\NAC"9;
%"TTL2G14"
"1","(-2900,2375)","0","mstr_ttl","I356";
;
CDS_SEC"2"
CDS_LIB"mstr_ttl"
ROOM"MIO_CHASSIS"
CDS_LOCATION"U2R1"
SEC"2"
SEC_TYPE"SMLF"
BOM_COST"MIO_CHASSIS"
PACK_TYPE"SMLF"
MATERIAL"IC"
VALUE"74LVC2G14"
PART_NUMBER"D18476-001"
LOCATION"U2R1"
POWER_GROUP"VCC=P3V3_STBY;GND=GND";
"A <SIZE-1..0>"
$PN"3"26;
"Y <SIZE -1..0> \B"
$PN"4"25;
%"TTL2G14"
"1","(-2150,2375)","0","mstr_ttl","I357";
;
CDS_SEC"1"
CDS_LIB"mstr_ttl"
BOM_COST"MIO_CHASSIS"
PACK_TYPE"SMLF"
SEC_TYPE"SMLF"
SEC"1"
CDS_LOCATION"U2R1"
ROOM"MIO_CHASSIS"
MATERIAL"IC"
LOCATION"U2R1"
VALUE"74LVC2G14"
PART_NUMBER"D18476-001"
POWER_GROUP"VCC=P3V3_STBY;GND=GND";
"A <SIZE-1..0>"
$PN"1"25;
"Y <SIZE -1..0> \B"
$PN"6"22;
%"RES"
"1","(-1400,2375)","0","mstr_discrete","I358";
;
CDS_SEC"1"
CDS_LOCATION"R2R10"
CDS_LIB"mstr_discrete"
SEC_TYPE"0402"
BOM_COST"MIO_CHASSIS"
SEC"1"
ROOM"MIO_CHASSIS"
WATTAGE"1/16W"
VALUE"33.2"
MATERIAL"CHIP"
TOLERANCE"1%"
LOCATION"R2R10"
PART_NUMBER"G21796-074"
PACK_TYPE"0402";
"B"
$PN"2"20;
"A"
$PN"1"22;
%"RES"
"1","(-7175,2200)","0","mstr_discrete","I361";
;
CDS_SEC"1"
CDS_LIB"mstr_discrete"
CDS_LOCATION"R8E19"
ROOM"BMC_MISC"
SEC"1"
SEC_TYPE"0402"
BOM_COST"SM_CONTROLLER"
VALUE"4.75K"
PART_NUMBER"G21796-072"
LOCATION"R8E19"
TOLERANCE"1%"
PACK_TYPE"0402"
MATERIAL"EMPTY"
WATTAGE"1/16W";
"B"
$PN"2"32;
"A"
$PN"1"1;
%"P3V3_STBY"
"1","(-5250,4675)","0","mstr_symbols","I362";
;
HDL_POWER"P3V3_STBY"
BODY_TYPE"PLUMBING"
SIZE"1B"
CDS_LIB"mstr_symbols"
VOLTAGE"3.3V";
"G\NAC"10;
%"RES"
"1","(-4925,4025)","0","mstr_discrete","I367";
;
CDS_SEC"1"
CDS_LIB"mstr_discrete"
CDS_LOCATION"R2U4"
ROOM"BMC_MISC"
SEC"1"
BOM_COST"SM_CONTROLLER"
SEC_TYPE"0402"
PART_NUMBER"G21796-072"
VALUE"4.75K"
TOLERANCE"1%"
PACK_TYPE"0402"
MATERIAL"CHIP"
WATTAGE"1/16W"
LOCATION"R2U4";
"B"
$PN"2"29;
"A"
$PN"1"10;
%"RES"
"1","(-6975,775)","0","mstr_discrete","I368";
;
CDS_SEC"1"
CDS_LIB"mstr_discrete"
SEC_TYPE"0402"
SEC"1"
CDS_LOCATION"R4R1"
ROOM"MIO_CHASSIS"
BOM_COST"MIO_CHASSIS"
WATTAGE"1/16W"
TOLERANCE"1%"
VALUE"1.00K"
MATERIAL"CHIP"
PART_NUMBER"G21796-026"
LOCATION"R4R1"
PACK_TYPE"0402";
"B"
$PN"2"40;
"A"
$PN"1"41;
%"P3V3_STBY"
"1","(-1825,3225)","0","mstr_symbols","I369";
;
HDL_POWER"P3V3_STBY"
VOLTAGE"3.3V"
CDS_LIB"mstr_symbols"
BODY_TYPE"PLUMBING"
SIZE"1B";
"G\NAC"11;
%"CAP_A"
"1","(-1825,2925)","0","dev_discrete","I370";
;
CDS_LIB"dev_discrete"
CDS_LOCATION"C2T3"
ROOM"MIO_CHASSIS"
BOM_COST"MIO_CHASSIS"
CDS_SEC"1"
SEC_TYPE"0402V"
SEC"1"
MATERIAL"X7R"
VOLTAGE"16V"
PACK_TYPE"0402V"
TOLERANCE"10%"
VALUE"0.1UF"
LOCATION"C2T3"
PART_NUMBER"A36096-030";
"B"
$PN"2"12;
"A"
$PN"1"11;
%"GND"
"1","(-1825,2625)","0","mstr_symbols","I371";
;
CDS_LIB"mstr_symbols"
VOLTAGE"0.0V"
HDL_POWER"GND"
BODY_TYPE"PLUMBING"
SIZE"1B";
"A\NAC"12;
%"TTL1G07_A"
"1","(-2800,1150)","0","mstr_ttl","I374";
;
CDS_SEC"1"
CDS_LOCATION"U8D2"
SEC"1"
SEC_TYPE"SOP"
PACK_TYPE"SOP"
CDS_LIB"mstr_ttl"
POWER_GROUP"VCC=P3V3_STBY;GND=GND"
PART_NUMBER"C88419-001"
MATERIAL"IC"
VALUE"74LVC1G07"
LOCATION"U8D2";
"Y"
$PN"4"23;
"A"
$PN"2"28;
%"CAP_A"
"1","(-500,1725)","0","dev_discrete","I376";
;
CDS_LIB"dev_discrete"
CDS_SEC"1"
CDS_LOCATION"C8D1"
SEC"1"
SEC_TYPE"0402V"
PACK_TYPE"0402V"
MATERIAL"X7R"
VOLTAGE"16V"
TOLERANCE"10%"
VALUE"0.1UF"
LOCATION"C8D1"
PART_NUMBER"A36096-030";
"B"
$PN"2"13;
"A"
$PN"1"14;
%"GND"
"1","(-500,1475)","0","mstr_symbols","I377";
;
BODY_TYPE"PLUMBING"
VOLTAGE"0.0V"
SIZE"1B"
CDS_LIB"mstr_symbols"
HDL_POWER"GND";
"A\NAC"13;
%"P3V3_STBY"
"1","(-500,1950)","0","mstr_symbols","I378";
;
HDL_POWER"P3V3_STBY"
BODY_TYPE"PLUMBING"
VOLTAGE"3.3V"
SIZE"1B"
CDS_LIB"mstr_symbols";
"G\NAC"14;
%"RES"
"1","(-1450,875)","0","mstr_discrete","I379";
;
CDS_SEC"1"
CDS_LIB"mstr_discrete"
CDS_LOCATION"R9E14"
SEC"1"
SEC_TYPE"0402"
LOCATION"R9E14"
PART_NUMBER"G21497-005"
WATTAGE"1/16W"
MATERIAL"CHIP"
PACK_TYPE"0402"
TOLERANCE"5%"
VALUE"0.0";
"B"
$PN"2"17;
"A"
$PN"1"16;
%"RES"
"1","(-7175,3425)","0","mstr_discrete","I382";
;
CDS_SEC"1"
CDS_LOCATION"R1L7"
CDS_LIB"mstr_discrete"
ROOM"BMC_MISC"
BOM_COST"SM_CONTROLLER"
SEC"1"
SEC_TYPE"0402"
VALUE"4.75K"
PART_NUMBER"G21796-072"
LOCATION"R1L7"
WATTAGE"1/16W"
MATERIAL"CHIP"
PACK_TYPE"0402"
TOLERANCE"1%";
"B"
$PN"2"31;
"A"
$PN"1"1;
%"P3V3_STBY"
"1","(-3950,2925)","0","mstr_symbols","I384";
;
HDL_POWER"P3V3_STBY"
BODY_TYPE"PLUMBING"
SIZE"1B"
CDS_LIB"mstr_symbols"
VOLTAGE"3.3V";
"G\NAC"15;
%"RES"
"2","(-3950,2650)","0","mstr_discrete","I385";
;
CDS_SEC"1"
CDS_LOCATION"R8E32"
CDS_LIB"mstr_discrete"
ROOM"MIO_CHASSIS"
SEC"1"
SEC_TYPE"0402"
BOM_COST"MIO_CHASSIS"
PART_NUMBER"G21796-072"
PACK_TYPE"0402"
TOLERANCE"1%"
WATTAGE"1/16W"
MATERIAL"CHIP"
LOCATION"R8E32"
VALUE"4.75K";
"A"
$PN"1"15;
"B"
$PN"2"27;
%"RES"
"1","(-1925,1150)","0","mstr_discrete","I386";
;
CDS_SEC"1"
CDS_LIB"mstr_discrete"
CDS_LOCATION"R8D22"
SEC_TYPE"0402"
BOM_COST"SM"
SEC"1"
ROOM"BMC_MISC"
MATERIAL"CHIP"
WATTAGE"1/16W"
VALUE"33.2"
PACK_TYPE"0402"
LOCATION"R8D22"
TOLERANCE"1%"
PART_NUMBER"G21796-074";
"B"
$PN"2"16;
"A"
$PN"1"23;
%"RES"
"1","(-1425,1375)","0","mstr_discrete","I388";
;
CDS_SEC"1"
CDS_LOCATION"R8D36"
CDS_LIB"mstr_discrete"
SEC_TYPE"0402"
BOM_COST"SM"
SEC"1"
ROOM"BMC_MISC"
MATERIAL"CHIP"
PACK_TYPE"0402"
WATTAGE"1/16W"
VALUE"33.2"
TOLERANCE"1%"
LOCATION"R8D36"
PART_NUMBER"G21796-074";
"B"
$PN"2"19;
"A"
$PN"1"23;
%"RES"
"2","(-1850,4025)","0","mstr_discrete","I97";
;
CDS_SEC"1"
CDS_LIB"mstr_discrete"
CDS_LOCATION"R2N27"
BOM_COST"SM_CONTROLLER"
ROOM"BMC_MISC"
SEC_TYPE"0402"
SEC"1"
WATTAGE"1/16W"
MATERIAL"CHIP"
PACK_TYPE"0402"
TOLERANCE"1%"
PART_NUMBER"G21796-072"
VALUE"4.75K"
LOCATION"R2N27";
"A"
$PN"1"2;
"B"
$PN"2"21;
END.
